# BASEBOARD_FAB2 (Tioga Pass) — schematic netlist excerpt (pin names and nets, part order shuffled) for the footprints in the layout excerpt that follows; sources: Cadence DE-HDL packaged netlist, KiCad conversion of Wiwynn_Tioga_Pass_MB.brd

J1A1  SCONN288_H44441004  SCONN  pkg PIP  page 87
  \12v\(1)  = P12V_NVDIMM_KLM
  VSS(93)  = GND
  DQ(4)  = M_M_DQ<5>
  VSS(92)  = GND
  DQ(0)  = M_M_DQ<1>
  VSS(91)  = GND
  DQS9P  = M_M_DQS_DP<9>
  DQS9N  = M_M_DQS_DN<9>
  VSS(90)  = GND
  DQ(6)  = M_M_DQ<7>
  VSS(89)  = GND
  DQ(2)  = M_M_DQ<3>
  VSS(88)  = GND
  DQ(12)  = M_M_DQ<13>
  VSS(87)  = GND
  DQ(8)  = M_M_DQ<9>
  VSS(86)  = GND
  DQS10P  = M_M_DQS_DP<10>
  DQS10N  = M_M_DQS_DN<10>
  VSS(85)  = GND
  DQ(14)  = M_M_DQ<15>
  VSS(84)  = GND
  DQ(10)  = M_M_DQ<11>
  VSS(83)  = GND
  DQ(20)  = M_M_DQ<21>
  VSS(82)  = GND
  DQ(16)  = M_M_DQ<17>
  VSS(81)  = GND
  DQS11P  = M_M_DQS_DP<11>
  DQS11N  = M_M_DQS_DN<11>
  VSS(80)  = GND
  DQ(22)  = M_M_DQ<23>
  VSS(79)  = GND
  DQ(18)  = M_M_DQ<19>
  VSS(78)  = GND
  DQ(28)  = M_M_DQ<29>
  VSS(77)  = GND
  DQ(24)  = M_M_DQ<25>
  VSS(76)  = GND
  DQS12P  = M_M_DQS_DP<12>
  DQS12N  = M_M_DQS_DN<12>
  VSS(75)  = GND
  DQ(30)  = M_M_DQ<31>
  VSS(74)  = GND
  DQ(26)  = M_M_DQ<27>
  VSS(73)  = GND
  CB(4)  = M_M_ECC<5>
  VSS(72)  = GND
  CB(0)  = M_M_ECC<1>
  VSS(71)  = GND
  DQS17P  = M_M_DQS_DP<17>
  DQS17N  = M_M_DQS_DN<17>
  VSS(70)  = GND
  CB(6)  = M_M_ECC<7>
  VSS(69)  = GND
  CB(2)  = M_M_ECC<3>
  VSS(68)  = GND
  RESET_N  = M_KLM_RST_N
  VDD(25)  = PVDDQ_KLM
  CKE(0)  = M_M_CKE<0>
  VDD(24)  = PVDDQ_KLM
  ACT_N  = M_M_ACT_N
  BG(0)  = M_M_BG<0>
  VDD(23)  = PVDDQ_KLM
  A12  = M_M_MA<12>
  A9  = M_M_MA<9>
  VDD(22)  = PVDDQ_KLM
  A8  = M_M_MA<8>
  A6  = M_M_MA<6>
  VDD(21)  = PVDDQ_KLM
  A3  = M_M_MA<3>
  A1  = M_M_MA<1>
  VDD(20)  = PVDDQ_KLM
  CK0P  = M_M_CLK_DP<0>
  CK0N  = M_M_CLK_DN<0>
  VDD(19)  = PVDDQ_KLM
  VTT(1)  = PVTT_KLM
  EVENT_N  = FM_DIMM_EVENT_COD_N
  A0  = M_M_MA<0>
  VDD(18)  = PVDDQ_KLM
  BA(0)  = M_M_BA<0>
  A16_RAS_N  = M_M_MA<16>
  VDD(17)  = PVDDQ_KLM
  S0_N  = M_M_CS_N<0>
  VDD(16)  = PVDDQ_KLM
  A15_CAS_N  = M_M_MA<15>
  ODT(0)  = M_M_ODT<0>
  VDD(15)  = PVDDQ_KLM
  S1_N  = M_M_CS_N<1>
  VDD(14)  = PVDDQ_KLM
  ODT(1)  = M_M_ODT<1>
  VDD(13)  = PVDDQ_KLM
  S2_N_C(0)  = M_M_CS_N<2>
  VSS(67)  = GND
  DQ(36)  = M_M_DQ<37>
  VSS(66)  = GND
  DQ(32)  = M_M_DQ<33>
  VSS(65)  = GND
  DQS13P  = M_M_DQS_DP<13>
  DQS13N  = M_M_DQS_DN<13>
  VSS(64)  = GND
  DQ(38)  = M_M_DQ<39>
  VSS(63)  = GND
  DQ(34)  = M_M_DQ<35>
  VSS(62)  = GND
  DQ(44)  = M_M_DQ<45>
  VSS(61)  = GND
  DQ(40)  = M_M_DQ<41>
  VSS(60)  = GND
  DQS14P  = M_M_DQS_DP<14>
  DQS14N  = M_M_DQS_DN<14>
  VSS(59)  = GND
  DQ(46)  = M_M_DQ<47>
  VSS(58)  = GND
  DQ(42)  = M_M_DQ<43>
  VSS(57)  = GND
  DQ(52)  = M_M_DQ<53>
  VSS(56)  = GND
  DQ(48)  = M_M_DQ<49>
  VSS(55)  = GND
  DQS15P  = M_M_DQS_DP<15>
  DQS15N  = M_M_DQS_DN<15>
  VSS(54)  = GND
  DQ(54)  = M_M_DQ<55>
  VSS(53)  = GND
  DQ(50)  = M_M_DQ<51>
  VSS(52)  = GND
  DQ(60)  = M_M_DQ<61>
  VSS(51)  = GND
  DQ(56)  = M_M_DQ<57>
  VSS(50)  = GND
  DQS16P  = M_M_DQS_DP<16>
  DQS16N  = M_M_DQS_DN<16>
  VSS(49)  = GND
  DQ(62)  = M_M_DQ<63>
  VSS(48)  = GND
  DQ(58)  = M_M_DQ<59>
  VSS(47)  = GND
  SA(0)  = GND
  SA(1)  = GND
  SCL  = SMB_DDR_KLM_VPP_SCL
  VPP(4)  = PVPP_KLM
  VPP(3)  = PVPP_KLM
  RFU(2)  = TP_CH_M_DIMM_M0_RFU_2
  \12v\(0)  = P12V_NVDIMM_KLM
  VREFCA  = M_M_VREF
  VSS(46)  = GND
  DQ(5)  = M_M_DQ<4>
  VSS(45)  = GND
  DQ(1)  = M_M_DQ<0>
  VSS(44)  = GND
  DQS0N  = M_M_DQS_DN<0>
  DQS0P  = M_M_DQS_DP<0>
  VSS(43)  = GND
  DQ(7)  = M_M_DQ<6>
  VSS(42)  = GND
  DQ(3)  = M_M_DQ<2>
  VSS(41)  = GND
  DQ(13)  = M_M_DQ<12>
  VSS(40)  = GND
  DQ(9)  = M_M_DQ<8>
  VSS(39)  = GND
  DQS1N  = M_M_DQS_DN<1>
  DQS1P  = M_M_DQS_DP<1>
  VSS(38)  = GND
  DQ(15)  = M_M_DQ<14>
  VSS(37)  = GND
  DQ(11)  = M_M_DQ<10>
  VSS(36)  = GND
  DQ(21)  = M_M_DQ<20>
  VSS(35)  = GND
  DQ(17)  = M_M_DQ<16>
  VSS(34)  = GND
  DQS2N  = M_M_DQS_DN<2>
  DQS2P  = M_M_DQS_DP<2>
  VSS(33)  = GND
  DQ(23)  = M_M_DQ<22>
  VSS(32)  = GND
  DQ(19)  = M_M_DQ<18>
  VSS(31)  = GND
  DQ(29)  = M_M_DQ<28>
  VSS(30)  = GND
  DQ(25)  = M_M_DQ<24>
  VSS(29)  = GND
  DQS3N  = M_M_DQS_DN<3>
  DQS3P  = M_M_DQS_DP<3>
  VSS(28)  = GND
  DQ(31)  = M_M_DQ<30>
  VSS(27)  = GND
  DQ(27)  = M_M_DQ<26>
  VSS(26)  = GND
  CB(5)  = M_M_ECC<4>
  VSS(25)  = GND
  CB(1)  = M_M_ECC<0>
  VSS(24)  = GND
  DQS8N  = M_M_DQS_DN<8>
  DQS8P  = M_M_DQS_DP<8>
  VSS(23)  = GND
  CB(7)  = M_M_ECC<6>
  VSS(22)  = GND
  CB(3)  = M_M_ECC<2>
  VSS(21)  = GND
  CKE(1)  = M_M_CKE<1>
  VDD(12)  = PVDDQ_KLM
  RFU(0)  = TP_CH_M_DIMM_M0_RFU_0
  VDD(11)  = PVDDQ_KLM
  BG(1)  = M_M_BG<1>
  ALERT_N  = M_M_ALERT_N
  VDD(10)  = PVDDQ_KLM
  A11  = M_M_MA<11>
  A7  = M_M_MA<7>
  VDD(9)  = PVDDQ_KLM
  A5  = M_M_MA<5>
  A4  = M_M_MA<4>
  VDD(8)  = PVDDQ_KLM
  A2  = M_M_MA<2>
  VDD(7)  = PVDDQ_KLM
  CK1P  = M_M_CLK_DP<1>
  CK1N  = M_M_CLK_DN<1>
  VDD(6)  = PVDDQ_KLM
  VTT(0)  = PVTT_KLM
  PAR  = M_M_PAR
  VDD(5)  = PVDDQ_KLM
  BA(1)  = M_M_BA<1>
  A10  = M_M_MA<10>
  VDD(4)  = PVDDQ_KLM
  RFU(1)  = TP_CH_M_DIMM_M0_RFU_1
  A14_WE_N  = M_M_MA<14>
  VDD(3)  = PVDDQ_KLM
  SAVE_N_NC  = FM_ADR_COMPLETE_KLM_N
  VDD(2)  = PVDDQ_KLM
  A13  = M_M_MA<13>
  VDD(1)  = PVDDQ_KLM
  A17  = M_M_MA<17>
  C(2)  = M_M_C<2>
  VDD(0)  = PVDDQ_KLM
  S3_N_C(1)  = M_M_CS_N<3>
  SA(2)  = PVPP_KLM
  VSS(20)  = GND
  DQ(37)  = M_M_DQ<36>
  VSS(19)  = GND
  DQ(33)  = M_M_DQ<32>
  VSS(18)  = GND
  DQS4N  = M_M_DQS_DN<4>
  DQS4P  = M_M_DQS_DP<4>
  VSS(17)  = GND
  DQ(39)  = M_M_DQ<38>
  VSS(16)  = GND
  DQ(35)  = M_M_DQ<34>
  VSS(15)  = GND
  DQ(45)  = M_M_DQ<44>
  VSS(14)  = GND
  DQ(41)  = M_M_DQ<40>
  VSS(13)  = GND
  DQS5N  = M_M_DQS_DN<5>
  DQS5P  = M_M_DQS_DP<5>
  VSS(12)  = GND
  DQ(47)  = M_M_DQ<46>
  VSS(11)  = GND
  DQ(43)  = M_M_DQ<42>
  VSS(10)  = GND
  DQ(53)  = M_M_DQ<52>
  VSS(9)  = GND
  DQ(49)  = M_M_DQ<48>
  VSS(8)  = GND
  DQS6N  = M_M_DQS_DN<6>
  DQS6P  = M_M_DQS_DP<6>
  VSS(7)  = GND
  DQ(55)  = M_M_DQ<54>
  VSS(6)  = GND
  DQ(51)  = M_M_DQ<50>
  VSS(5)  = GND
  DQ(61)  = M_M_DQ<60>
  VSS(4)  = GND
  DQ(57)  = M_M_DQ<56>
  VSS(3)  = GND
  DQS7N  = M_M_DQS_DN<7>
  DQS7P  = M_M_DQS_DP<7>
  VSS(2)  = GND
  DQ(63)  = M_M_DQ<62>
  VSS(1)  = GND
  DQ(59)  = M_M_DQ<58>
  VSS(0)  = GND
  VDDSPD  = PVPP_KLM
  SDA  = SMB_DDR_KLM_VPP_SDA
  VPP(1)  = PVPP_KLM
  VPP(0)  = PVPP_KLM
  VPP(2)  = PVPP_KLM

(kicad_pcb
	(version 20260206)
	(generator "pcbnew")
	(generator_version "10.0")
	(general
		(thickness 1.6)
		(legacy_teardrops no)
	)
	(paper "A4")
	(title_block
		(title "Wiwynn_Tioga_Pass_MB.brd")
		(comment 1 "Tioga Pass / footprint 830 of 4770 (J1A1), pads 52-101 of 291")
	)
	(layers
		(0 "F.Cu" signal "TOP")
		(4 "In1.Cu" signal "L2GND")
		(6 "In2.Cu" signal "L3")
		(8 "In3.Cu" signal "L4GND")
		(10 "In4.Cu" signal "L5")
		(12 "In5.Cu" signal "L6GND")
		(14 "In6.Cu" signal "L7VCC")
		(16 "In7.Cu" signal "L8VCC")
		(18 "In8.Cu" signal "L9GND")
		(20 "In9.Cu" signal "L10")
		(22 "In10.Cu" signal "L11GND")
		(24 "In11.Cu" signal "L12")
		(26 "In12.Cu" signal "L13GND")
		(2 "B.Cu" signal "BOTTOM")
		(9 "F.Adhes" user "F.Adhesive")
		(11 "B.Adhes" user "B.Adhesive")
		(13 "F.Paste" user "Package Geometry/Pastemask Top")
		(15 "B.Paste" user "Package Geometry/Pastemask Bottom")
		(5 "F.SilkS" user "Ref Des/Silkscreen Top")
		(7 "B.SilkS" user "Ref Des/Silkscreen Bottom")
		(1 "F.Mask" user "Board Geometry/Soldermask Top")
		(3 "B.Mask" user "Board Geometry/Soldermask Bottom")
		(17 "Dwgs.User" user "User.Drawings")
		(19 "Cmts.User" user "User.Comments")
		(21 "Eco1.User" user "User.Eco1")
		(23 "Eco2.User" user "User.Eco2")
		(25 "Edge.Cuts" user "Board Geometry/Outline")
		(27 "Margin" user)
		(31 "F.CrtYd" user "Package Geometry/Place Bound Top")
		(29 "B.CrtYd" user "Package Geometry/Place Bound Bottom")
		(35 "F.Fab" user "Ref Des/Assembly Top")
		(33 "B.Fab" user "Ref Des/Assembly Bottom")
	)
	(footprint ""
		(layer "F.Cu")
		(at 29.699458 -152.273 90)
		(property "Reference" "J1A1"
			(at -2.572512 42.563542 0)
			(unlocked yes)
			(layer "F.SilkS")
			(effects
				(font
					(size 0.7874 0.5842)
					(thickness 0.1524)
				)
				(justify left)
			)
		)
		(property "Value" ""
			(at 0 0 90)
			(layer "F.Fab")
			(effects
				(font
					(size 1.27 1.27)
				)
			)
		)
		(duplicate_pad_numbers_are_jumpers no)
		(pad "49" smd rect
			(at 0 40.80002 90)
			(size 1.8034 0.508)
			(layers "F.Cu" "F.Mask" "F.Paste")
			(net "M_M_ECC<1>")
		)
		(pad "50" smd rect
			(at 0 41.649904 90)
			(size 1.8034 0.508)
			(layers "F.Cu" "F.Mask" "F.Paste")
			(net "GND")
		)
		(pad "51" smd rect
			(at 0 42.500042 90)
			(size 1.8034 0.508)
			(layers "F.Cu" "F.Mask" "F.Paste")
			(net "M_M_DQS_DP<17>")
		)
		(pad "52" smd rect
			(at 0 43.349926 90)
			(size 1.8034 0.508)
			(layers "F.Cu" "F.Mask" "F.Paste")
			(net "M_M_DQS_DN<17>")
		)
		(pad "53" smd rect
			(at 0 44.200064 90)
			(size 1.8034 0.508)
			(layers "F.Cu" "F.Mask" "F.Paste")
			(net "GND")
		)
		(pad "54" smd rect
			(at 0 45.049948 90)
			(size 1.8034 0.508)
			(layers "F.Cu" "F.Mask" "F.Paste")
			(net "M_M_ECC<7>")
		)
		(pad "55" smd rect
			(at 0 45.900086 90)
			(size 1.8034 0.508)
			(layers "F.Cu" "F.Mask" "F.Paste")
			(net "GND")
		)
		(pad "56" smd rect
			(at 0 46.74997 90)
			(size 1.8034 0.508)
			(layers "F.Cu" "F.Mask" "F.Paste")
			(net "M_M_ECC<3>")
		)
		(pad "57" smd rect
			(at 0 47.600108 90)
			(size 1.8034 0.508)
			(layers "F.Cu" "F.Mask" "F.Paste")
			(net "GND")
		)
		(pad "58" smd rect
			(at 0 48.449992 90)
			(size 1.8034 0.508)
			(layers "F.Cu" "F.Mask" "F.Paste")
			(net "M_KLM_RST_N")
		)
		(pad "59" smd rect
			(at 0 49.299876 90)
			(size 1.8034 0.508)
			(layers "F.Cu" "F.Mask" "F.Paste")
			(net "PVDDQ_KLM")
		)
		(pad "60" smd rect
			(at 0 50.150014 90)
			(size 1.8034 0.508)
			(layers "F.Cu" "F.Mask" "F.Paste")
			(net "M_M_CKE<0>")
		)
		(pad "61" smd rect
			(at 0 50.999898 90)
			(size 1.8034 0.508)
			(layers "F.Cu" "F.Mask" "F.Paste")
			(net "PVDDQ_KLM")
		)
		(pad "62" smd rect
			(at 0 51.850036 90)
			(size 1.8034 0.508)
			(layers "F.Cu" "F.Mask" "F.Paste")
			(net "M_M_ACT_N")
		)
		(pad "63" smd rect
			(at 0 52.69992 90)
			(size 1.8034 0.508)
			(layers "F.Cu" "F.Mask" "F.Paste")
			(net "M_M_BG<0>")
		)
		(pad "64" smd rect
			(at 0 53.550058 90)
			(size 1.8034 0.508)
			(layers "F.Cu" "F.Mask" "F.Paste")
			(net "PVDDQ_KLM")
		)
		(pad "65" smd rect
			(at 0 54.399942 90)
			(size 1.8034 0.508)
			(layers "F.Cu" "F.Mask" "F.Paste")
			(net "M_M_MA<12>")
		)
		(pad "66" smd rect
			(at 0 55.25008 90)
			(size 1.8034 0.508)
			(layers "F.Cu" "F.Mask" "F.Paste")
			(net "M_M_MA<9>")
		)
		(pad "67" smd rect
			(at 0 56.099964 90)
			(size 1.8034 0.508)
			(layers "F.Cu" "F.Mask" "F.Paste")
			(net "PVDDQ_KLM")
		)
		(pad "68" smd rect
			(at 0 56.950102 90)
			(size 1.8034 0.508)
			(layers "F.Cu" "F.Mask" "F.Paste")
			(net "M_M_MA<8>")
		)
		(pad "69" smd rect
			(at 0 57.799986 90)
			(size 1.8034 0.508)
			(layers "F.Cu" "F.Mask" "F.Paste")
			(net "M_M_MA<6>")
		)
		(pad "70" smd rect
			(at 0 58.650124 90)
			(size 1.8034 0.508)
			(layers "F.Cu" "F.Mask" "F.Paste")
			(net "PVDDQ_KLM")
		)
		(pad "71" smd rect
			(at 0 59.500008 90)
			(size 1.8034 0.508)
			(layers "F.Cu" "F.Mask" "F.Paste")
			(net "M_M_MA<3>")
		)
		(pad "72" smd rect
			(at 0 60.349892 90)
			(size 1.8034 0.508)
			(layers "F.Cu" "F.Mask" "F.Paste")
			(net "M_M_MA<1>")
		)
		(pad "73" smd rect
			(at 0 61.20003 90)
			(size 1.8034 0.508)
			(layers "F.Cu" "F.Mask" "F.Paste")
			(net "PVDDQ_KLM")
		)
		(pad "74" smd rect
			(at 0 62.049914 90)
			(size 1.8034 0.508)
			(layers "F.Cu" "F.Mask" "F.Paste")
			(net "M_M_CLK_DP<0>")
		)
		(pad "75" smd rect
			(at 0 62.900052 90)
			(size 1.8034 0.508)
			(layers "F.Cu" "F.Mask" "F.Paste")
			(net "M_M_CLK_DN<0>")
		)
		(pad "76" smd rect
			(at 0 63.749936 90)
			(size 1.8034 0.508)
			(layers "F.Cu" "F.Mask" "F.Paste")
			(net "PVDDQ_KLM")
		)
		(pad "77" smd rect
			(at 0 64.600074 90)
			(size 1.8034 0.508)
			(layers "F.Cu" "F.Mask" "F.Paste")
			(net "PVTT_KLM")
		)
		(pad "78" smd rect
			(at 0 70.550024 90)
			(size 1.8034 0.508)
			(layers "F.Cu" "F.Mask" "F.Paste")
			(net "FM_DIMM_EVENT_COD_N")
		)
		(pad "79" smd rect
			(at 0 71.399908 90)
			(size 1.8034 0.508)
			(layers "F.Cu" "F.Mask" "F.Paste")
			(net "M_M_MA<0>")
		)
		(pad "80" smd rect
			(at 0 72.250046 90)
			(size 1.8034 0.508)
			(layers "F.Cu" "F.Mask" "F.Paste")
			(net "PVDDQ_KLM")
		)
		(pad "81" smd rect
			(at 0 73.09993 90)
			(size 1.8034 0.508)
			(layers "F.Cu" "F.Mask" "F.Paste")
			(net "M_M_BA<0>")
		)
		(pad "82" smd rect
			(at 0 73.950068 90)
			(size 1.8034 0.508)
			(layers "F.Cu" "F.Mask" "F.Paste")
			(net "M_M_MA<16>")
		)
		(pad "83" smd rect
			(at 0 74.799952 90)
			(size 1.8034 0.508)
			(layers "F.Cu" "F.Mask" "F.Paste")
			(net "PVDDQ_KLM")
		)
		(pad "84" smd rect
			(at 0 75.65009 90)
			(size 1.8034 0.508)
			(layers "F.Cu" "F.Mask" "F.Paste")
			(net "M_M_CS_N<0>")
		)
		(pad "85" smd rect
			(at 0 76.499974 90)
			(size 1.8034 0.508)
			(layers "F.Cu" "F.Mask" "F.Paste")
			(net "PVDDQ_KLM")
		)
		(pad "86" smd rect
			(at 0 77.350112 90)
			(size 1.8034 0.508)
			(layers "F.Cu" "F.Mask" "F.Paste")
			(net "M_M_MA<15>")
		)
		(pad "87" smd rect
			(at 0 78.199996 90)
			(size 1.8034 0.508)
			(layers "F.Cu" "F.Mask" "F.Paste")
			(net "M_M_ODT<0>")
		)
		(pad "88" smd rect
			(at 0 79.04988 90)
			(size 1.8034 0.508)
			(layers "F.Cu" "F.Mask" "F.Paste")
			(net "PVDDQ_KLM")
		)
		(pad "89" smd rect
			(at 0 79.900018 90)
			(size 1.8034 0.508)
			(layers "F.Cu" "F.Mask" "F.Paste")
			(net "M_M_CS_N<1>")
		)
		(pad "90" smd rect
			(at 0 80.749902 90)
			(size 1.8034 0.508)
			(layers "F.Cu" "F.Mask" "F.Paste")
			(net "PVDDQ_KLM")
		)
		(pad "91" smd rect
			(at 0 81.60004 90)
			(size 1.8034 0.508)
			(layers "F.Cu" "F.Mask" "F.Paste")
			(net "M_M_ODT<1>")
		)
		(pad "92" smd rect
			(at 0 82.449924 90)
			(size 1.8034 0.508)
			(layers "F.Cu" "F.Mask" "F.Paste")
			(net "PVDDQ_KLM")
		)
		(pad "93" smd rect
			(at 0 83.300062 90)
			(size 1.8034 0.508)
			(layers "F.Cu" "F.Mask" "F.Paste")
			(net "M_M_CS_N<2>")
		)
		(pad "94" smd rect
			(at 0 84.149946 90)
			(size 1.8034 0.508)
			(layers "F.Cu" "F.Mask" "F.Paste")
			(net "GND")
		)
		(pad "95" smd rect
			(at 0 85.000084 90)
			(size 1.8034 0.508)
			(layers "F.Cu" "F.Mask" "F.Paste")
			(net "M_M_DQ<37>")
		)
		(pad "96" smd rect
			(at 0 85.849968 90)
			(size 1.8034 0.508)
			(layers "F.Cu" "F.Mask" "F.Paste")
			(net "GND")
		)
		(pad "97" smd rect
			(at 0 86.700106 90)
			(size 1.8034 0.508)
			(layers "F.Cu" "F.Mask" "F.Paste")
			(net "M_M_DQ<33>")
		)
		(pad "98" smd rect
			(at 0 87.54999 90)
			(size 1.8034 0.508)
			(layers "F.Cu" "F.Mask" "F.Paste")
			(net "GND")
		)
	)
)
